FILE_TYPE = CONNECTIVITY;
{Allegro Design Entry HDL 17.4-2019 S026 (4007227) 1/17/2022}
"PAGE_NUMBER" = 249;
0"NC";
1"GND\g";
2"GND\g";
3"GND\g";
4"GND\g";
5"GND\g";
6"GND\g";
7"GND\g";
8"GND\g";
9"GND\g";
10"SMB_BMC_GPU_EN";
11"SMB_1_BMC_GPU_SDA"CDS_PHYS_NET_NAME"SMB_1_BMC_GPU_SDA";
12"SMB_2_BMC_GPU_BUF_R_SDA"CDS_PHYS_NET_NAME"SMB_2_BMC_GPU_BUF_R_SDA";
13"I3C_BMC_SWB_BUF_SDA"CDS_PHYS_NET_NAME"I3C_BMC_SWB_BUF_SDA";
14"SMB_2_BMC_GPU_R_SDA";
15"SMB_2_BMC_GPU_R_SCL";
16"SMB_2_BMC_GPU_BUF_R_SCL"CDS_PHYS_NET_NAME"SMB_2_BMC_GPU_BUF_R_SCL";
17"P3V3_AUX\g";
18"SMB_BMC_SWB_EN_R2"CDS_PHYS_NET_NAME"SMB_BMC_SWB_EN_R2";
19"I3C_BMC_SWB_R_SCL"CDS_PHYS_NET_NAME"I3C_BMC_SWB_R_SCL";
20"I3C_BMC_SWB_R_SDA"CDS_PHYS_NET_NAME"I3C_BMC_SWB_R_SDA";
21"SMB_BMC_SWB_R_SDA";
22"SMB_BMC_SWB_R_SCL";
23"SMB_BMC_SWB_EN_R"CDS_PHYS_NET_NAME"SMB_BMC_SWB_EN_R";
24"P3V3_AUX\g";
25"P3V3_AUX\g";
26"I3C_BMC_SWB_BUF_R_SCL"CDS_PHYS_NET_NAME"I3C_BMC_SWB_BUF_R_SCL";
27"I3C_BMC_SWB_BUF_R_SDA"CDS_PHYS_NET_NAME"I3C_BMC_SWB_BUF_R_SDA";
28"I3C_BMC_SWB_BUF_SCL"CDS_PHYS_NET_NAME"I3C_BMC_SWB_BUF_SCL";
29"I3C_BMC_SWB_SDA";
30"I3C_BMC_SWB_SCL";
31"SMB_BMC_SWB_EN";
32"P3V3_AUX\g";
33"GND\g";
34"P3V3_AUX\g";
35"P3V3_AUX\g";
36"P3V3_AUX\g";
37"P3V3_AUX\g";
38"SMB_BMC_SWB_EN";
39"SMB_BMC_SWB_BUF_R_SCL"CDS_PHYS_NET_NAME"SMB_BMC_SWB_BUF_R_SCL";
40"SMB_BMC_SWB_BUF_R_SDA"CDS_PHYS_NET_NAME"SMB_BMC_SWB_BUF_R_SDA";
41"SMB_BMC_GPU_EN_R1"CDS_PHYS_NET_NAME"SMB_BMC_GPU_EN_R1";
42"SMB_1_BMC_GPU_R_SDA"CDS_PHYS_NET_NAME"SMB_1_BMC_GPU_R_SDA";
43"SMB_1_BMC_GPU_R_SCL"CDS_PHYS_NET_NAME"SMB_1_BMC_GPU_R_SCL";
44"SMB_1_BMC_GPU_BUF_SCL"CDS_PHYS_NET_NAME"SMB_1_BMC_GPU_BUF_SCL";
45"SMB_1_BMC_GPU_BUF_SDA"CDS_PHYS_NET_NAME"SMB_1_BMC_GPU_BUF_SDA";
46"SMB_1_BMC_GPU_BUF_R_SDA"CDS_PHYS_NET_NAME"SMB_1_BMC_GPU_BUF_R_SDA";
47"SMB_1_BMC_GPU_BUF_R_SCL"CDS_PHYS_NET_NAME"SMB_1_BMC_GPU_BUF_R_SCL";
48"SMB_BMC_SWB_BUF_SCL"CDS_PHYS_NET_NAME"SMB_BMC_SWB_BUF_SCL";
49"SMB_BMC_SWB_BUF_SDA"CDS_PHYS_NET_NAME"SMB_BMC_SWB_BUF_SDA";
50"SMB_2_BMC_GPU_BUF_SDA"CDS_PHYS_NET_NAME"SMB_2_BMC_GPU_BUF_SDA";
51"SMB_2_BMC_GPU_BUF_SCL"CDS_PHYS_NET_NAME"SMB_2_BMC_GPU_BUF_SCL";
52"SMB_1_BMC_GPU_SCL"CDS_PHYS_NET_NAME"SMB_1_BMC_GPU_SCL";
53"SMB_BMC_GPU_EN_R3"CDS_PHYS_NET_NAME"SMB_BMC_GPU_EN_R3";
54"SMB_BMC_GPU_EN";
55"SMB_2_BMC_GPU_SCL"CDS_PHYS_NET_NAME"SMB_2_BMC_GPU_SCL";
56"SMB_BMC_SWB_SCL"CDS_PHYS_NET_NAME"SMB_BMC_SWB_SCL";
57"SMB_BMC_SWB_SDA"CDS_PHYS_NET_NAME"SMB_BMC_SWB_SDA";
58"SMB_2_BMC_GPU_SDA"CDS_PHYS_NET_NAME"SMB_2_BMC_GPU_SDA";
%"Q_RES"
"1","(-7825,2750)","0","pure_quanta","I12";
;
LOCATION"R2992"
$SEC"1"
CDS_SEC"1"
VALUE"0"
TOLERANCE"5%"
MATERIAL"CHIP"
WATTAGE"1/16W"
PACK_TYPE"0402LF"
CDS_LIB"pure_quanta"
PART_NUMBER"CS00002JB13";
"B"
$PN"2"53;
"A"
$PN"1"54;
%"Q_RES"
"1","(-7825,2650)","0","pure_quanta","I13";
;
LOCATION"R3107"
$SEC"1"
CDS_SEC"1"
TOLERANCE"5%"
MATERIAL"CHIP"
VALUE"0"
PACK_TYPE"0402LF"
WATTAGE"1/16W"
CDS_LIB"pure_quanta"
PART_NUMBER"CS00002JB13";
"B"
$PN"2"15;
"A"
$PN"1"55;
%"Q_RES"
"1","(-7825,2550)","0","pure_quanta","I14";
;
LOCATION"R3108"
$SEC"1"
CDS_SEC"1"
VALUE"0"
TOLERANCE"5%"
MATERIAL"CHIP"
PACK_TYPE"0402LF"
WATTAGE"1/16W"
CDS_LIB"pure_quanta"
PART_NUMBER"CS00002JB13";
"B"
$PN"2"14;
"A"
$PN"1"58;
%"LTC4307CMS8"
"1","(-6500,2600)","0","pure_quanta","I15";
;
LOCATION"U200"
$SEC"1"
CDS_SEC"1"
MATERIAL"IC"
PART_TYPE"SMLF"
VALUE"LTC4307CMS8"
CDS_LIB"pure_quanta"
NEEDS_NO_SIZE"TRUE"
PART_NUMBER"AL004307000";
"READY"
$PN"5"0;
"SDA_OUT"
$PN"7"12;
"SCL_OUT"
$PN"2"16;
"VCC"
$PN"8"17;
"GND"
$PN"4"1;
"SDA_IN"
$PN"6"14;
"SCL_IN"
$PN"3"15;
"ENABLE"
$PN"1"53;
%"UNIVERSAL_GND"
"1","(-6900,2325)","0","pure_quanta_power","I16";
;
CDS_LIB"pure_quanta_power"
HDL_POWER"GND";
"A"1;
%"Q_RES"
"1","(-6525,2125)","0","pure_quanta","I17";
;
LOCATION"R2987"
$SEC"1"
CDS_SEC"1"
VALUE"0"
TOLERANCE"5%"
PACK_TYPE"0402LF"
WATTAGE"1/16W"
MATERIAL"EMPTY"
CDS_LIB"pure_quanta"
PART_NUMBER"CS00002JB13";
"B"
$PN"2"12;
"A"
$PN"1"14;
%"Q_RES"
"1","(-6525,2200)","0","pure_quanta","I18";
;
LOCATION"R2986"
$SEC"1"
CDS_SEC"1"
VALUE"0"
MATERIAL"EMPTY"
CDS_LIB"pure_quanta"
PACK_TYPE"0402LF"
TOLERANCE"5%"
WATTAGE"1/16W"
PART_NUMBER"CS00002JB13";
"B"
$PN"2"16;
"A"
$PN"1"15;
%"UNIVERSAL_GND"
"1","(-6700,3475)","0","pure_quanta_power","I19";
;
CDS_LIB"pure_quanta_power"
HDL_POWER"GND";
"A"2;
%"Q_RES"
"2","(-6700,3675)","0","pure_quanta","I23";
;
LOCATION"R4603"
$SEC"1"
CDS_SEC"1"
VALUE"10K"
TOLERANCE"1%"
WATTAGE"1/16W"
MATERIAL"CHIP"
PACK_TYPE"0402LF"
CDS_LIB"pure_quanta"
PART_NUMBER"CS31002FB08";
"A"
$PN"1"10;
"B"
$PN"2"2;
%"Q_RES"
"1","(-5700,1225)","0","pure_quanta","I25";
;
LOCATION"R3112"
$SEC"1"
CDS_SEC"1"
VALUE"33.2"
MATERIAL"CHIP"
TOLERANCE"1%"
CDS_LIB"pure_quanta"
PACK_TYPE"0402LF"
WATTAGE"1/16W"
PART_NUMBER"CS03322FB03";
"B"
$PN"2"19;
"A"
$PN"1"30;
%"Q_RES"
"1","(-5700,1325)","0","pure_quanta","I26";
;
LOCATION"R2676"
$SEC"1"
CDS_SEC"1"
WATTAGE"1/16W"
PACK_TYPE"0402LF"
MATERIAL"CHIP"
TOLERANCE"5%"
VALUE"0"
CDS_LIB"pure_quanta"
PART_NUMBER"CS00002JB13";
"B"
$PN"2"18;
"A"
$PN"1"31;
%"Q_RES"
"1","(-3975,475)","0","pure_quanta","I27";
;
LOCATION"R2706"
$SEC"1"
CDS_SEC"1"
VALUE"0"
MATERIAL"CHIP"
CDS_LIB"pure_quanta"
PACK_TYPE"0402LF"
TOLERANCE"5%"
WATTAGE"1/16W"
PART_NUMBER"CS00002JB13";
"B"
$PN"2"27;
"A"
$PN"1"20;
%"Q_RES"
"1","(-3975,400)","0","pure_quanta","I28";
;
LOCATION"R2725"
$SEC"1"
CDS_SEC"1"
TOLERANCE"5%"
WATTAGE"1/16W"
VALUE"0"
PACK_TYPE"0402LF"
MATERIAL"CHIP"
CDS_LIB"pure_quanta"
PART_NUMBER"CS00002JB13";
"B"
$PN"2"26;
"A"
$PN"1"19;
%"UNIVERSAL_GND"
"1","(-4475,900)","0","pure_quanta_power","I29";
;
CDS_LIB"pure_quanta_power"
HDL_POWER"GND";
"A"3;
%"LTC4307CMS8"
"1","(-3925,1175)","0","pure_quanta","I30";
;
LOCATION"U176"
$SEC"1"
CDS_SEC"1"
PART_TYPE"SMLF"
MATERIAL"EMPTY"
VALUE"LTC4307CMS8"
NEEDS_NO_SIZE"TRUE"
CDS_LIB"pure_quanta"
PART_NUMBER"AL004307000";
"READY"
$PN"5"0;
"SDA_OUT"
$PN"7"27;
"SCL_OUT"
$PN"2"26;
"VCC"
$PN"8"25;
"GND"
$PN"4"3;
"SDA_IN"
$PN"6"20;
"SCL_IN"
$PN"3"19;
"ENABLE"
$PN"1"18;
%"UNIVERSAL_GND"
"1","(-5775,2775)","0","pure_quanta_power","I31";
;
CDS_LIB"pure_quanta_power"
HDL_POWER"GND";
"A"4;
%"Q_CAP"
"1","(-5775,3000)","0","pure_quanta","I32";
;
LOCATION"C1796"
$SEC"1"
CDS_SEC"1"
PACK_TYPE"0402"
MATERIAL"X7R"
VOLTAGE"25V"
TOLERANCE"10%"
VALUE"0.1UF"
CDS_LIB"pure_quanta"
PART_NUMBER"CH4104K1B00";
"B"
$PN"2"4;
"A"
$PN"1"17;
%"UNIVERSAL_POWER"
"1","(-5950,3300)","0","pure_quanta_power","I33";
;
HDL_POWER"P3V3_AUX"
CDS_LIB"pure_quanta_power";
"A"17;
%"Q_RES"
"1","(-5750,3900)","0","pure_quanta","I34";
;
LOCATION"R3110"
$SEC"1"
CDS_SEC"1"
WATTAGE"1/16W"
MATERIAL"CHIP"
TOLERANCE"5%"
PACK_TYPE"0402LF"
VALUE"0"
CDS_LIB"pure_quanta"
PART_NUMBER"CS00002JB13";
"B"
$PN"2"42;
"A"
$PN"1"11;
%"Q_RES"
"1","(-5750,4000)","0","pure_quanta","I35";
;
LOCATION"R3109"
$SEC"1"
CDS_SEC"1"
TOLERANCE"5%"
VALUE"0"
MATERIAL"CHIP"
CDS_LIB"pure_quanta"
PACK_TYPE"0402LF"
WATTAGE"1/16W"
PART_NUMBER"CS00002JB13";
"B"
$PN"2"43;
"A"
$PN"1"52;
%"Q_RES"
"2","(-5025,2975)","0","pure_quanta","I36";
;
LOCATION"R3521"
$SEC"1"
CDS_SEC"1"
TOLERANCE"1%"
VALUE"54.9K"
PACK_TYPE"0402LF"
WATTAGE"1/16W"
MATERIAL"CHIP"
CDS_LIB"pure_quanta"
PART_NUMBER"CS35492FB03";
"A"
$PN"1"32;
"B"
$PN"2"16;
%"Q_RES"
"2","(-4775,2975)","0","pure_quanta","I37";
;
LOCATION"R3522"
$SEC"1"
CDS_SEC"1"
MATERIAL"CHIP"
TOLERANCE"1%"
VALUE"54.9K"
PACK_TYPE"0402LF"
WATTAGE"1/16W"
CDS_LIB"pure_quanta"
PART_NUMBER"CS35492FB03";
"A"
$PN"1"32;
"B"
$PN"2"12;
%"Q_RES"
"1","(-4475,2650)","0","pure_quanta","I38";
;
LOCATION"R2990"
$SEC"1"
CDS_SEC"1"
MATERIAL"CHIP"
VALUE"33.2"
TOLERANCE"1%"
WATTAGE"1/16W"
PACK_TYPE"0402LF"
CDS_LIB"pure_quanta"
PART_NUMBER"CS03322FB03";
"B"
$PN"2"51;
"A"
$PN"1"16;
%"Q_RES"
"1","(-4475,2550)","0","pure_quanta","I39";
;
LOCATION"R2991"
$SEC"1"
CDS_SEC"1"
MATERIAL"CHIP"
TOLERANCE"1%"
VALUE"33.2"
WATTAGE"1/16W"
PACK_TYPE"0402LF"
CDS_LIB"pure_quanta"
PART_NUMBER"CS03322FB03";
"B"
$PN"2"50;
"A"
$PN"1"12;
%"UNIVERSAL_POWER"
"1","(-5025,3300)","0","pure_quanta_power","I40";
;
HDL_POWER"P3V3_AUX"
CDS_LIB"pure_quanta_power";
"A"32;
%"UNIVERSAL_GND"
"1","(-4375,3675)","0","pure_quanta_power","I41";
;
CDS_LIB"pure_quanta_power"
HDL_POWER"GND";
"A"33;
%"LTC4307CMS8"
"1","(-3900,3950)","0","pure_quanta","I42";
;
LOCATION"U194"
$SEC"1"
CDS_SEC"1"
PART_TYPE"SMLF"
MATERIAL"IC"
VALUE"LTC4307CMS8"
CDS_LIB"pure_quanta"
NEEDS_NO_SIZE"TRUE"
PART_NUMBER"AL004307000";
"READY"
$PN"5"0;
"SDA_OUT"
$PN"7"46;
"SCL_OUT"
$PN"2"47;
"VCC"
$PN"8"36;
"GND"
$PN"4"33;
"SDA_IN"
$PN"6"42;
"SCL_IN"
$PN"3"43;
"ENABLE"
$PN"1"41;
%"Q_RES"
"1","(-7775,5275)","0","pure_quanta","I43";
;
LOCATION"R3106"
$SEC"1"
CDS_SEC"1"
VALUE"0"
TOLERANCE"5%"
MATERIAL"CHIP"
PACK_TYPE"0402LF"
WATTAGE"1/16W"
CDS_LIB"pure_quanta"
PART_NUMBER"CS00002JB13";
"B"
$PN"2"21;
"A"
$PN"1"57;
%"Q_RES"
"1","(-7775,5375)","0","pure_quanta","I44";
;
LOCATION"R3105"
$SEC"1"
CDS_SEC"1"
VALUE"0"
TOLERANCE"5%"
MATERIAL"CHIP"
CDS_LIB"pure_quanta"
WATTAGE"1/16W"
PACK_TYPE"0402LF"
PART_NUMBER"CS00002JB13";
"B"
$PN"2"22;
"A"
$PN"1"56;
%"Q_RES"
"1","(-7775,5475)","0","pure_quanta","I45";
;
LOCATION"R2707"
$SEC"1"
CDS_SEC"1"
MATERIAL"CHIP"
VALUE"0"
TOLERANCE"5%"
CDS_LIB"pure_quanta"
PACK_TYPE"0402LF"
WATTAGE"1/16W"
PART_NUMBER"CS00002JB13";
"B"
$PN"2"23;
"A"
$PN"1"38;
%"UNIVERSAL_GND"
"1","(-6675,5050)","0","pure_quanta_power","I46";
;
CDS_LIB"pure_quanta_power"
HDL_POWER"GND";
"A"5;
%"Q_RES"
"1","(-6300,4925)","0","pure_quanta","I47";
;
LOCATION"R2705"
$SEC"1"
CDS_SEC"1"
MATERIAL"EMPTY"
VALUE"0"
CDS_LIB"pure_quanta"
PACK_TYPE"0402LF"
TOLERANCE"5%"
WATTAGE"1/16W"
PART_NUMBER"CS00002JB13";
"B"
$PN"2"39;
"A"
$PN"1"22;
%"Q_RES"
"1","(-6300,4850)","0","pure_quanta","I48";
;
LOCATION"R2724"
$SEC"1"
CDS_SEC"1"
TOLERANCE"5%"
PACK_TYPE"0402LF"
WATTAGE"1/16W"
VALUE"0"
MATERIAL"EMPTY"
CDS_LIB"pure_quanta"
PART_NUMBER"CS00002JB13";
"B"
$PN"2"40;
"A"
$PN"1"21;
%"LTC4307CMS8"
"1","(-6275,5325)","0","pure_quanta","I49";
;
LOCATION"U175"
$SEC"1"
CDS_SEC"1"
MATERIAL"IC"
PART_TYPE"SMLF"
VALUE"LTC4307CMS8"
NEEDS_NO_SIZE"TRUE"
CDS_LIB"pure_quanta"
PART_NUMBER"AL004307000";
"READY"
$PN"5"0;
"SDA_OUT"
$PN"7"40;
"SCL_OUT"
$PN"2"39;
"VCC"
$PN"8"24;
"GND"
$PN"4"5;
"SDA_IN"
$PN"6"21;
"SCL_IN"
$PN"3"22;
"ENABLE"
$PN"1"23;
%"Q_RES"
"1","(-5750,4100)","0","pure_quanta","I50";
;
LOCATION"R2899"
$SEC"1"
CDS_SEC"1"
VALUE"0"
MATERIAL"CHIP"
TOLERANCE"5%"
WATTAGE"1/16W"
PACK_TYPE"0402LF"
CDS_LIB"pure_quanta"
PART_NUMBER"CS00002JB13";
"B"
$PN"2"41;
"A"
$PN"1"10;
%"UNIVERSAL_GND"
"1","(-5650,5500)","0","pure_quanta_power","I51";
;
CDS_LIB"pure_quanta_power"
HDL_POWER"GND";
"A"6;
%"Q_CAP"
"1","(-5650,5725)","0","pure_quanta","I52";
;
LOCATION"C1707"
$SEC"1"
CDS_SEC"1"
PACK_TYPE"0402"
MATERIAL"X7R"
TOLERANCE"10%"
VOLTAGE"25V"
VALUE"0.1UF"
CDS_LIB"pure_quanta"
PART_NUMBER"CH4104K1B00";
"B"
$PN"2"6;
"A"
$PN"1"24;
%"UNIVERSAL_POWER"
"1","(-5825,6025)","0","pure_quanta_power","I53";
;
HDL_POWER"P3V3_AUX"
CDS_LIB"pure_quanta_power";
"A"24;
%"Q_RES"
"2","(-4800,5700)","0","pure_quanta","I54";
;
LOCATION"R2667"
$SEC"1"
CDS_SEC"1"
VALUE"2.2K"
PACK_TYPE"0402LF"
TOLERANCE"5%"
MATERIAL"CHIP"
WATTAGE"1/16W"
CDS_LIB"pure_quanta"
PART_NUMBER"CS22202JB07";
"A"
$PN"1"34;
"B"
$PN"2"39;
%"UNIVERSAL_POWER"
"1","(-4800,6025)","0","pure_quanta_power","I55";
;
HDL_POWER"P3V3_AUX"
CDS_LIB"pure_quanta_power";
"A"34;
%"Q_RES"
"1","(-4250,5275)","0","pure_quanta","I56";
;
LOCATION"R2672"
$SEC"1"
CDS_SEC"1"
MATERIAL"CHIP"
VALUE"33.2"
TOLERANCE"1%"
WATTAGE"1/16W"
PACK_TYPE"0402LF"
CDS_LIB"pure_quanta"
PART_NUMBER"CS03322FB03";
"B"
$PN"2"49;
"A"
$PN"1"40;
%"Q_RES"
"2","(-4550,5700)","0","pure_quanta","I57";
;
LOCATION"R2669"
$SEC"1"
CDS_SEC"1"
MATERIAL"CHIP"
WATTAGE"1/16W"
PACK_TYPE"0402LF"
TOLERANCE"5%"
VALUE"2.2K"
CDS_LIB"pure_quanta"
PART_NUMBER"CS22202JB07";
"A"
$PN"1"34;
"B"
$PN"2"40;
%"Q_RES"
"1","(-4250,5375)","0","pure_quanta","I58";
;
LOCATION"R2671"
$SEC"1"
CDS_SEC"1"
VALUE"33.2"
PACK_TYPE"0402LF"
MATERIAL"CHIP"
TOLERANCE"1%"
WATTAGE"1/16W"
CDS_LIB"pure_quanta"
PART_NUMBER"CS03322FB03";
"B"
$PN"2"48;
"A"
$PN"1"39;
%"UNIVERSAL_GND"
"1","(-3275,1400)","0","pure_quanta_power","I59";
;
CDS_LIB"pure_quanta_power"
HDL_POWER"GND";
"A"7;
%"UNIVERSAL_POWER"
"1","(-3450,1925)","0","pure_quanta_power","I60";
;
HDL_POWER"P3V3_AUX"
CDS_LIB"pure_quanta_power";
"A"25;
%"Q_CAP"
"1","(-3275,1625)","0","pure_quanta","I61";
;
LOCATION"C1708"
$SEC"1"
CDS_SEC"1"
PACK_TYPE"0402"
MATERIAL"X7R"
TOLERANCE"10%"
VOLTAGE"25V"
VALUE"0.1UF"
CDS_LIB"pure_quanta"
PART_NUMBER"CH4104K1B00";
"B"
$PN"2"7;
"A"
$PN"1"25;
%"Q_RES"
"2","(-2350,1600)","0","pure_quanta","I62";
;
LOCATION"R2668"
$SEC"1"
CDS_SEC"1"
VALUE"4.7K"
MATERIAL"EMPTY"
WATTAGE"1/16W"
TOLERANCE"5%"
PACK_TYPE"0402LF"
CDS_LIB"pure_quanta"
PART_NUMBER"CS24702JB10";
"A"
$PN"1"35;
"B"
$PN"2"27;
%"Q_RES"
"2","(-2100,1600)","0","pure_quanta","I63";
;
LOCATION"R2670"
$SEC"1"
CDS_SEC"1"
PACK_TYPE"0402LF"
MATERIAL"EMPTY"
WATTAGE"1/16W"
VALUE"4.7K"
TOLERANCE"5%"
CDS_LIB"pure_quanta"
PART_NUMBER"CS24702JB10";
"A"
$PN"1"35;
"B"
$PN"2"26;
%"UNIVERSAL_POWER"
"1","(-2350,1925)","0","pure_quanta_power","I64";
;
HDL_POWER"P3V3_AUX"
CDS_LIB"pure_quanta_power";
"A"35;
%"Q_RES"
"1","(-3925,3475)","0","pure_quanta","I67";
;
LOCATION"R2894"
$SEC"1"
CDS_SEC"1"
TOLERANCE"5%"
MATERIAL"EMPTY"
PACK_TYPE"0402LF"
VALUE"0"
WATTAGE"1/16W"
CDS_LIB"pure_quanta"
PART_NUMBER"CS00002JB13";
"B"
$PN"2"46;
"A"
$PN"1"42;
%"Q_RES"
"1","(-3925,3550)","0","pure_quanta","I68";
;
LOCATION"R2893"
$SEC"1"
CDS_SEC"1"
VALUE"0"
MATERIAL"EMPTY"
WATTAGE"1/16W"
TOLERANCE"5%"
PACK_TYPE"0402LF"
CDS_LIB"pure_quanta"
PART_NUMBER"CS00002JB13";
"B"
$PN"2"47;
"A"
$PN"1"43;
%"Q_RES"
"1","(-1800,1225)","0","pure_quanta","I69";
;
LOCATION"R2675"
$SEC"1"
CDS_SEC"1"
MATERIAL"CHIP"
VALUE"33.2"
TOLERANCE"1%"
WATTAGE"1/16W"
PACK_TYPE"0402LF"
CDS_LIB"pure_quanta"
PART_NUMBER"CS03322FB03";
"B"
$PN"2"28;
"A"
$PN"1"26;
%"UNIVERSAL_GND"
"1","(-6475,675)","0","pure_quanta_power","I7";
;
CDS_LIB"pure_quanta_power"
HDL_POWER"GND";
"A"8;
%"Q_RES"
"1","(-1875,3900)","0","pure_quanta","I73";
;
LOCATION"R2898"
$SEC"1"
CDS_SEC"1"
VALUE"33.2"
MATERIAL"CHIP"
TOLERANCE"1%"
CDS_LIB"pure_quanta"
PACK_TYPE"0402LF"
WATTAGE"1/16W"
PART_NUMBER"CS03322FB03";
"B"
$PN"2"45;
"A"
$PN"1"46;
%"Q_RES"
"1","(-1875,4000)","0","pure_quanta","I74";
;
LOCATION"R2897"
$SEC"1"
CDS_SEC"1"
WATTAGE"1/16W"
PACK_TYPE"0402LF"
TOLERANCE"1%"
VALUE"33.2"
MATERIAL"CHIP"
CDS_LIB"pure_quanta"
PART_NUMBER"CS03322FB03";
"B"
$PN"2"44;
"A"
$PN"1"47;
%"UNIVERSAL_GND"
"1","(-3175,4125)","0","pure_quanta_power","I77";
;
CDS_LIB"pure_quanta_power"
HDL_POWER"GND";
"A"9;
%"Q_CAP"
"1","(-3175,4350)","0","pure_quanta","I78";
;
LOCATION"C1766"
$SEC"1"
CDS_SEC"1"
TOLERANCE"10%"
VOLTAGE"25V"
MATERIAL"X7R"
VALUE"0.1UF"
PACK_TYPE"0402"
CDS_LIB"pure_quanta"
PART_NUMBER"CH4104K1B00";
"B"
$PN"2"9;
"A"
$PN"1"36;
%"UNIVERSAL_POWER"
"1","(-3350,4650)","0","pure_quanta_power","I79";
;
HDL_POWER"P3V3_AUX"
CDS_LIB"pure_quanta_power";
"A"36;
%"Q_RES"
"2","(-6475,875)","0","pure_quanta","I8";
;
LOCATION"R2666"
$SEC"1"
CDS_SEC"1"
WATTAGE"1/16W"
MATERIAL"CHIP"
TOLERANCE"1%"
VALUE"10K"
PACK_TYPE"0402LF"
CDS_LIB"pure_quanta"
PART_NUMBER"CS31002FB08";
"A"
$PN"1"31;
"B"
$PN"2"8;
%"Q_RES"
"2","(-2425,4325)","0","pure_quanta","I80";
;
LOCATION"R3523"
$SEC"1"
CDS_SEC"1"
WATTAGE"1/16W"
TOLERANCE"1%"
VALUE"54.9K"
PACK_TYPE"0402LF"
MATERIAL"CHIP"
CDS_LIB"pure_quanta"
PART_NUMBER"CS35492FB03";
"A"
$PN"1"37;
"B"
$PN"2"47;
%"Q_RES"
"2","(-2175,4325)","0","pure_quanta","I81";
;
LOCATION"R3524"
$SEC"1"
CDS_SEC"1"
PACK_TYPE"0402LF"
VALUE"54.9K"
TOLERANCE"1%"
WATTAGE"1/16W"
MATERIAL"CHIP"
CDS_LIB"pure_quanta"
PART_NUMBER"CS35492FB03";
"A"
$PN"1"37;
"B"
$PN"2"46;
%"UNIVERSAL_POWER"
"1","(-2425,4650)","0","pure_quanta_power","I82";
;
HDL_POWER"P3V3_AUX"
CDS_LIB"pure_quanta_power";
"A"37;
%"Q_RES"
"1","(-5700,1125)","0","pure_quanta","I85";
;
LOCATION"R3111"
$SEC"1"
CDS_SEC"1"
PACK_TYPE"0402LF"
MATERIAL"CHIP"
TOLERANCE"5%"
VALUE"0"
WATTAGE"1/16W"
CDS_LIB"pure_quanta"
PART_NUMBER"CS00002JB13";
"B"
$PN"2"20;
"A"
$PN"1"29;
%"Q_RES"
"1","(-1800,1125)","0","pure_quanta","I86";
;
LOCATION"R2674"
$SEC"1"
CDS_SEC"1"
MATERIAL"CHIP"
TOLERANCE"5%"
VALUE"27"
WATTAGE"1/16W"
PACK_TYPE"0402LF"
CDS_LIB"pure_quanta"
PART_NUMBER"CS02702JB02";
"B"
$PN"2"13;
"A"
$PN"1"27;
END.
